(kicad_pcb
	(version 20260206)
	(generator "pcbnew")
	(generator_version "10.0")
	(general
		(thickness 1.6)
		(legacy_teardrops no)
	)
	(paper "A4")
	(title_block
		(title "04192023_DAF0TMB3IC0_F0TG_MB_C_brd_V02_OCP.brd")
		(comment 1 "Grand Teton / footprints 5059-5069 of 8354")
	)
	(layers
		(0 "F.Cu" signal "TOP")
		(4 "In1.Cu" signal "GND")
		(6 "In2.Cu" signal "IN1")
		(8 "In3.Cu" signal "GND1")
		(10 "In4.Cu" signal "IN2")
		(12 "In5.Cu" signal "GND2")
		(14 "In6.Cu" signal "IN3")
		(16 "In7.Cu" signal "GND3")
		(18 "In8.Cu" signal "VCC")
		(20 "In9.Cu" signal "VCC1")
		(22 "In10.Cu" signal "GND4")
		(24 "In11.Cu" signal "IN4")
		(26 "In12.Cu" signal "GND5")
		(28 "In13.Cu" signal "IN5")
		(30 "In14.Cu" signal "GND6")
		(32 "In15.Cu" signal "IN6")
		(34 "In16.Cu" signal "GND7")
		(2 "B.Cu" signal "BOTTOM")
		(9 "F.Adhes" user "F.Adhesive")
		(11 "B.Adhes" user "B.Adhesive")
		(13 "F.Paste" user "Package Geometry/Pastemask Top")
		(15 "B.Paste" user "Package Geometry/Pastemask Bottom")
		(5 "F.SilkS" user "Ref Des/Silkscreen Top")
		(7 "B.SilkS" user "Ref Des/Silkscreen Bottom")
		(1 "F.Mask" user "Board Geometry/Soldermask Top")
		(3 "B.Mask" user "Board Geometry/Soldermask Bottom")
		(17 "Dwgs.User" user "User.Drawings")
		(19 "Cmts.User" user "User.Comments")
		(21 "Eco1.User" user "User.Eco1")
		(23 "Eco2.User" user "User.Eco2")
		(25 "Edge.Cuts" user "Board Geometry/Outline")
		(27 "Margin" user)
		(31 "F.CrtYd" user "Package Geometry/Place Bound Top")
		(29 "B.CrtYd" user "Package Geometry/Place Bound Bottom")
		(35 "F.Fab" user "Ref Des/Assembly Top")
		(33 "B.Fab" user "Ref Des/Assembly Bottom")
	)
	(footprint ""
		(layer "B.Cu")
		(at 151.806148 -386.766562 90)
		(property "Reference" "C390"
			(at 0 0 90)
			(layer "B.SilkS")
			(hide yes)
			(effects
				(font
					(size 1.27 1.27)
				)
				(justify mirror)
			)
		)
		(property "Value" ""
			(at 0 0 90)
			(layer "B.Fab")
			(effects
				(font
					(size 1.27 1.27)
				)
				(justify mirror)
			)
		)
		(duplicate_pad_numbers_are_jumpers no)
		(fp_line
			(start 0.299974 -0.150114)
			(end -0.299974 -0.150114)
			(stroke
				(width 0.1)
				(type default)
			)
			(layer "B.Fab")
		)
		(fp_line
			(start -0.299974 -0.150114)
			(end -0.299974 0.150114)
			(stroke
				(width 0.1)
				(type default)
			)
			(layer "B.Fab")
		)
		(fp_line
			(start 0.299974 0.150114)
			(end 0.299974 -0.150114)
			(stroke
				(width 0.1)
				(type default)
			)
			(layer "B.Fab")
		)
		(fp_line
			(start -0.299974 0.150114)
			(end 0.299974 0.150114)
			(stroke
				(width 0.1)
				(type default)
			)
			(layer "B.Fab")
		)
		(pad "1" smd rect
			(at 0.2667 0 270)
			(size 0.3048 0.381)
			(layers "B.Cu" "B.Mask" "B.Paste")
			(net "P0V9_CPU1_RT2_2A_2D")
		)
		(pad "2" smd rect
			(at -0.2667 0 270)
			(size 0.3048 0.381)
			(layers "B.Cu" "B.Mask" "B.Paste")
			(net "GND")
		)
	)
	(footprint ""
		(layer "B.Cu")
		(at 165.146228 -388.011162 -90)
		(property "Reference" "C395"
			(at 0 0 90)
			(layer "B.SilkS")
			(hide yes)
			(effects
				(font
					(size 1.27 1.27)
				)
				(justify mirror)
			)
		)
		(property "Value" ""
			(at 0 0 90)
			(layer "B.Fab")
			(effects
				(font
					(size 1.27 1.27)
				)
				(justify mirror)
			)
		)
		(duplicate_pad_numbers_are_jumpers no)
		(fp_line
			(start -0.299974 0.150114)
			(end 0.299974 0.150114)
			(stroke
				(width 0.1)
				(type default)
			)
			(layer "B.Fab")
		)
		(fp_line
			(start 0.299974 0.150114)
			(end 0.299974 -0.150114)
			(stroke
				(width 0.1)
				(type default)
			)
			(layer "B.Fab")
		)
		(fp_line
			(start -0.299974 -0.150114)
			(end -0.299974 0.150114)
			(stroke
				(width 0.1)
				(type default)
			)
			(layer "B.Fab")
		)
		(fp_line
			(start 0.299974 -0.150114)
			(end -0.299974 -0.150114)
			(stroke
				(width 0.1)
				(type default)
			)
			(layer "B.Fab")
		)
		(pad "1" smd rect
			(at 0.2667 0 90)
			(size 0.3048 0.381)
			(layers "B.Cu" "B.Mask" "B.Paste")
			(net "P0V9_CPU1_RT2_2A")
		)
		(pad "2" smd rect
			(at -0.2667 0 90)
			(size 0.3048 0.381)
			(layers "B.Cu" "B.Mask" "B.Paste")
			(net "GND")
		)
	)
	(footprint ""
		(layer "B.Cu")
		(at 351.645982 -396.393162 -90)
		(property "Reference" "C659"
			(at 0 0 90)
			(layer "B.SilkS")
			(hide yes)
			(effects
				(font
					(size 1.27 1.27)
				)
				(justify mirror)
			)
		)
		(property "Value" ""
			(at 0 0 90)
			(layer "B.Fab")
			(effects
				(font
					(size 1.27 1.27)
				)
				(justify mirror)
			)
		)
		(duplicate_pad_numbers_are_jumpers no)
		(fp_line
			(start -0.299974 0.150114)
			(end 0.299974 0.150114)
			(stroke
				(width 0.1)
				(type default)
			)
			(layer "B.Fab")
		)
		(fp_line
			(start 0.299974 0.150114)
			(end 0.299974 -0.150114)
			(stroke
				(width 0.1)
				(type default)
			)
			(layer "B.Fab")
		)
		(fp_line
			(start -0.299974 -0.150114)
			(end -0.299974 0.150114)
			(stroke
				(width 0.1)
				(type default)
			)
			(layer "B.Fab")
		)
		(fp_line
			(start 0.299974 -0.150114)
			(end -0.299974 -0.150114)
			(stroke
				(width 0.1)
				(type default)
			)
			(layer "B.Fab")
		)
		(pad "1" smd rect
			(at 0.2667 0 90)
			(size 0.3048 0.381)
			(layers "B.Cu" "B.Mask" "B.Paste")
			(net "P0V9_CPU0_RT1_2A")
		)
		(pad "2" smd rect
			(at -0.2667 0 90)
			(size 0.3048 0.381)
			(layers "B.Cu" "B.Mask" "B.Paste")
			(net "GND")
		)
	)
	(footprint ""
		(layer "B.Cu")
		(at 352.163126 -416.899344 90)
		(property "Reference" "C6563"
			(at 0 0 90)
			(layer "B.SilkS")
			(hide yes)
			(effects
				(font
					(size 1.27 1.27)
				)
				(justify mirror)
			)
		)
		(property "Value" ""
			(at 0 0 90)
			(layer "B.Fab")
			(effects
				(font
					(size 1.27 1.27)
				)
				(justify mirror)
			)
		)
		(duplicate_pad_numbers_are_jumpers no)
		(fp_line
			(start 0.299974 -0.150114)
			(end -0.299974 -0.150114)
			(stroke
				(width 0.1)
				(type default)
			)
			(layer "B.Fab")
		)
		(fp_line
			(start -0.299974 -0.150114)
			(end -0.299974 0.150114)
			(stroke
				(width 0.1)
				(type default)
			)
			(layer "B.Fab")
		)
		(fp_line
			(start 0.299974 0.150114)
			(end 0.299974 -0.150114)
			(stroke
				(width 0.1)
				(type default)
			)
			(layer "B.Fab")
		)
		(fp_line
			(start -0.299974 0.150114)
			(end 0.299974 0.150114)
			(stroke
				(width 0.1)
				(type default)
			)
			(layer "B.Fab")
		)
		(pad "1" smd rect
			(at 0.2667 0 270)
			(size 0.3048 0.381)
			(layers "B.Cu" "B.Mask" "B.Paste")
			(net "P5E_CPU0_P1_TX_BUF_C_DP<15>")
		)
		(pad "2" smd rect
			(at -0.2667 0 270)
			(size 0.3048 0.381)
			(layers "B.Cu" "B.Mask" "B.Paste")
			(net "P5E_CPU0_P1_TX_BUF_DP<15>")
		)
	)
	(footprint ""
		(layer "B.Cu")
		(at 28.46324 -193.996564)
		(property "Reference" "C152"
			(at 0 0 0)
			(layer "B.SilkS")
			(hide yes)
			(effects
				(font
					(size 1.27 1.27)
				)
				(justify mirror)
			)
		)
		(property "Value" ""
			(at 0 0 0)
			(layer "B.Fab")
			(effects
				(font
					(size 1.27 1.27)
				)
				(justify mirror)
			)
		)
		(duplicate_pad_numbers_are_jumpers no)
		(fp_line
			(start -0.7874 -0.4064)
			(end -0.7874 0.4064)
			(stroke
				(width 0.1524)
				(type default)
			)
			(layer "B.SilkS")
		)
		(fp_line
			(start -0.7874 0.4064)
			(end 0.7874 0.4064)
			(stroke
				(width 0.1524)
				(type default)
			)
			(layer "B.SilkS")
		)
		(fp_line
			(start 0.7874 -0.4064)
			(end -0.7874 -0.4064)
			(stroke
				(width 0.1524)
				(type default)
			)
			(layer "B.SilkS")
		)
		(fp_line
			(start 0.7874 0.4064)
			(end 0.7874 -0.4064)
			(stroke
				(width 0.1524)
				(type default)
			)
			(layer "B.SilkS")
		)
		(fp_line
			(start -0.67945 -0.3048)
			(end -0.67945 0.3048)
			(stroke
				(width 0.1)
				(type default)
			)
			(layer "B.Fab")
		)
		(fp_line
			(start -0.67945 0.3048)
			(end -0.120396 0.3048)
			(stroke
				(width 0.1)
				(type default)
			)
			(layer "B.Fab")
		)
		(fp_line
			(start -0.12065 -0.3048)
			(end -0.67945 -0.3048)
			(stroke
				(width 0.1)
				(type default)
			)
			(layer "B.Fab")
		)
		(fp_line
			(start -0.12065 -0.2794)
			(end -0.12065 -0.3048)
			(stroke
				(width 0.1)
				(type default)
			)
			(layer "B.Fab")
		)
		(fp_line
			(start -0.120396 0.2794)
			(end 0.12065 0.2794)
			(stroke
				(width 0.1)
				(type default)
			)
			(layer "B.Fab")
		)
		(fp_line
			(start -0.120396 0.3048)
			(end -0.120396 0.2794)
			(stroke
				(width 0.1)
				(type default)
			)
			(layer "B.Fab")
		)
		(fp_line
			(start 0.12065 -0.305054)
			(end 0.12065 -0.2794)
			(stroke
				(width 0.1)
				(type default)
			)
			(layer "B.Fab")
		)
		(fp_line
			(start 0.12065 -0.2794)
			(end -0.12065 -0.2794)
			(stroke
				(width 0.1)
				(type default)
			)
			(layer "B.Fab")
		)
		(fp_line
			(start 0.12065 0.2794)
			(end 0.12065 0.3048)
			(stroke
				(width 0.1)
				(type default)
			)
			(layer "B.Fab")
		)
		(fp_line
			(start 0.12065 0.3048)
			(end 0.67945 0.3048)
			(stroke
				(width 0.1)
				(type default)
			)
			(layer "B.Fab")
		)
		(fp_line
			(start 0.67945 -0.305054)
			(end 0.12065 -0.305054)
			(stroke
				(width 0.1)
				(type default)
			)
			(layer "B.Fab")
		)
		(fp_line
			(start 0.67945 0.3048)
			(end 0.67945 -0.305054)
			(stroke
				(width 0.1)
				(type default)
			)
			(layer "B.Fab")
		)
		(pad "1" smd circle
			(at 0.40005 0 180)
			(size 0 0)
			(layers "B.Cu" "B.Mask" "B.Paste")
			(net "P3V3_AUX")
		)
		(pad "2" smd circle
			(at -0.40005 0 180)
			(size 0 0)
			(layers "B.Cu" "B.Mask" "B.Paste")
			(net "GND")
		)
	)
	(footprint ""
		(layer "B.Cu")
		(at 299.265594 -391.88136 180)
		(property "Reference" "R973"
			(at 0 0 0)
			(layer "B.SilkS")
			(hide yes)
			(effects
				(font
					(size 1.27 1.27)
				)
				(justify mirror)
			)
		)
		(property "Value" ""
			(at 0 0 0)
			(layer "B.Fab")
			(effects
				(font
					(size 1.27 1.27)
				)
				(justify mirror)
			)
		)
		(duplicate_pad_numbers_are_jumpers no)
		(fp_line
			(start 0.32512 0.175006)
			(end 0.32512 -0.175006)
			(stroke
				(width 0.1)
				(type default)
			)
			(layer "B.Fab")
		)
		(fp_line
			(start 0.32512 -0.175006)
			(end -0.32512 -0.175006)
			(stroke
				(width 0.1)
				(type default)
			)
			(layer "B.Fab")
		)
		(fp_line
			(start -0.32512 0.175006)
			(end 0.32512 0.175006)
			(stroke
				(width 0.1)
				(type default)
			)
			(layer "B.Fab")
		)
		(fp_line
			(start -0.32512 -0.175006)
			(end -0.32512 0.175006)
			(stroke
				(width 0.1)
				(type default)
			)
			(layer "B.Fab")
		)
		(pad "1" smd rect
			(at 0.2667 0)
			(size 0.3048 0.381)
			(layers "B.Cu" "B.Mask" "B.Paste")
			(net "RT_CPU0_P0_SCAN_MODE")
		)
		(pad "2" smd rect
			(at -0.2667 0 180)
			(size 0.3048 0.381)
			(layers "B.Cu" "B.Mask" "B.Paste")
			(net "GND")
		)
	)
	(footprint ""
		(layer "B.Cu")
		(at 125.418342 -388.011162 -90)
		(property "Reference" "C444"
			(at 0 0 90)
			(layer "B.SilkS")
			(hide yes)
			(effects
				(font
					(size 1.27 1.27)
				)
				(justify mirror)
			)
		)
		(property "Value" ""
			(at 0 0 90)
			(layer "B.Fab")
			(effects
				(font
					(size 1.27 1.27)
				)
				(justify mirror)
			)
		)
		(duplicate_pad_numbers_are_jumpers no)
		(fp_line
			(start -0.299974 0.150114)
			(end 0.299974 0.150114)
			(stroke
				(width 0.1)
				(type default)
			)
			(layer "B.Fab")
		)
		(fp_line
			(start 0.299974 0.150114)
			(end 0.299974 -0.150114)
			(stroke
				(width 0.1)
				(type default)
			)
			(layer "B.Fab")
		)
		(fp_line
			(start -0.299974 -0.150114)
			(end -0.299974 0.150114)
			(stroke
				(width 0.1)
				(type default)
			)
			(layer "B.Fab")
		)
		(fp_line
			(start 0.299974 -0.150114)
			(end -0.299974 -0.150114)
			(stroke
				(width 0.1)
				(type default)
			)
			(layer "B.Fab")
		)
		(pad "1" smd rect
			(at 0.2667 0 90)
			(size 0.3048 0.381)
			(layers "B.Cu" "B.Mask" "B.Paste")
			(net "P1V8_CPU1_RT3_1A_1D")
		)
		(pad "2" smd rect
			(at -0.2667 0 90)
			(size 0.3048 0.381)
			(layers "B.Cu" "B.Mask" "B.Paste")
			(net "GND")
		)
	)
	(footprint ""
		(layer "B.Cu")
		(at 419.089586 -425.82338 180)
		(property "Reference" "R1217"
			(at 0 0 0)
			(layer "B.SilkS")
			(hide yes)
			(effects
				(font
					(size 1.27 1.27)
				)
				(justify mirror)
			)
		)
		(property "Value" ""
			(at 0 0 0)
			(layer "B.Fab")
			(effects
				(font
					(size 1.27 1.27)
				)
				(justify mirror)
			)
		)
		(duplicate_pad_numbers_are_jumpers no)
		(fp_line
			(start 0.32512 0.175006)
			(end 0.32512 -0.175006)
			(stroke
				(width 0.1)
				(type default)
			)
			(layer "B.Fab")
		)
		(fp_line
			(start 0.32512 -0.175006)
			(end -0.32512 -0.175006)
			(stroke
				(width 0.1)
				(type default)
			)
			(layer "B.Fab")
		)
		(fp_line
			(start -0.32512 0.175006)
			(end 0.32512 0.175006)
			(stroke
				(width 0.1)
				(type default)
			)
			(layer "B.Fab")
		)
		(fp_line
			(start -0.32512 -0.175006)
			(end -0.32512 0.175006)
			(stroke
				(width 0.1)
				(type default)
			)
			(layer "B.Fab")
		)
		(pad "1" smd rect
			(at 0.2667 0)
			(size 0.3048 0.381)
			(layers "B.Cu" "B.Mask" "B.Paste")
			(net "GND")
		)
		(pad "2" smd rect
			(at -0.2667 0 180)
			(size 0.3048 0.381)
			(layers "B.Cu" "B.Mask" "B.Paste")
			(net "RT_ROM_MUX8_OE_N")
		)
	)
	(footprint ""
		(layer "B.Cu")
		(at 403.981158 -327.987152)
		(property "Reference" "R737"
			(at 0 0 0)
			(layer "B.SilkS")
			(hide yes)
			(effects
				(font
					(size 1.27 1.27)
				)
				(justify mirror)
			)
		)
		(property "Value" ""
			(at 0 0 0)
			(layer "B.Fab")
			(effects
				(font
					(size 1.27 1.27)
				)
				(justify mirror)
			)
		)
		(duplicate_pad_numbers_are_jumpers no)
		(fp_line
			(start -0.7874 -0.4064)
			(end -0.7874 0.4064)
			(stroke
				(width 0.1524)
				(type default)
			)
			(layer "B.SilkS")
		)
		(fp_line
			(start -0.7874 0.4064)
			(end 0.7874 0.4064)
			(stroke
				(width 0.1524)
				(type default)
			)
			(layer "B.SilkS")
		)
		(fp_line
			(start 0.7874 -0.4064)
			(end -0.7874 -0.4064)
			(stroke
				(width 0.1524)
				(type default)
			)
			(layer "B.SilkS")
		)
		(fp_line
			(start 0.7874 0.4064)
			(end 0.7874 -0.4064)
			(stroke
				(width 0.1524)
				(type default)
			)
			(layer "B.SilkS")
		)
		(fp_line
			(start -0.67945 -0.3048)
			(end -0.67945 0.3048)
			(stroke
				(width 0.1)
				(type default)
			)
			(layer "B.Fab")
		)
		(fp_line
			(start -0.67945 0.3048)
			(end -0.120396 0.3048)
			(stroke
				(width 0.1)
				(type default)
			)
			(layer "B.Fab")
		)
		(fp_line
			(start -0.12065 -0.3048)
			(end -0.67945 -0.3048)
			(stroke
				(width 0.1)
				(type default)
			)
			(layer "B.Fab")
		)
		(fp_line
			(start -0.12065 -0.2794)
			(end -0.12065 -0.3048)
			(stroke
				(width 0.1)
				(type default)
			)
			(layer "B.Fab")
		)
		(fp_line
			(start -0.120396 0.2794)
			(end 0.12065 0.2794)
			(stroke
				(width 0.1)
				(type default)
			)
			(layer "B.Fab")
		)
		(fp_line
			(start -0.120396 0.3048)
			(end -0.120396 0.2794)
			(stroke
				(width 0.1)
				(type default)
			)
			(layer "B.Fab")
		)
		(fp_line
			(start 0.12065 -0.305054)
			(end 0.12065 -0.2794)
			(stroke
				(width 0.1)
				(type default)
			)
			(layer "B.Fab")
		)
		(fp_line
			(start 0.12065 -0.2794)
			(end -0.12065 -0.2794)
			(stroke
				(width 0.1)
				(type default)
			)
			(layer "B.Fab")
		)
		(fp_line
			(start 0.12065 0.2794)
			(end 0.12065 0.3048)
			(stroke
				(width 0.1)
				(type default)
			)
			(layer "B.Fab")
		)
		(fp_line
			(start 0.12065 0.3048)
			(end 0.67945 0.3048)
			(stroke
				(width 0.1)
				(type default)
			)
			(layer "B.Fab")
		)
		(fp_line
			(start 0.67945 -0.305054)
			(end 0.12065 -0.305054)
			(stroke
				(width 0.1)
				(type default)
			)
			(layer "B.Fab")
		)
		(fp_line
			(start 0.67945 0.3048)
			(end 0.67945 -0.305054)
			(stroke
				(width 0.1)
				(type default)
			)
			(layer "B.Fab")
		)
		(pad "1" smd circle
			(at 0.40005 0 180)
			(size 0 0)
			(layers "B.Cu" "B.Mask" "B.Paste")
			(net "PVDD18_S5_P0")
		)
		(pad "2" smd circle
			(at -0.40005 0 180)
			(size 0 0)
			(layers "B.Cu" "B.Mask" "B.Paste")
			(net "CPU0_ROM_TYPE_SELECT")
		)
	)
	(footprint ""
		(layer "B.Cu")
		(at 226.777042 -315.95568 -90)
		(property "Reference" "PC6528"
			(at 0 0 90)
			(layer "B.SilkS")
			(hide yes)
			(effects
				(font
					(size 1.27 1.27)
				)
				(justify mirror)
			)
		)
		(property "Value" ""
			(at 0 0 90)
			(layer "B.Fab")
			(effects
				(font
					(size 1.27 1.27)
				)
				(justify mirror)
			)
		)
		(duplicate_pad_numbers_are_jumpers no)
		(fp_line
			(start -1.524 0.762)
			(end 1.524 0.762)
			(stroke
				(width 0.1524)
				(type default)
			)
			(layer "B.SilkS")
		)
		(fp_line
			(start 1.524 0.762)
			(end 1.524 -0.762)
			(stroke
				(width 0.1524)
				(type default)
			)
			(layer "B.SilkS")
		)
		(fp_line
			(start -1.524 -0.762)
			(end -1.524 0.762)
			(stroke
				(width 0.1524)
				(type default)
			)
			(layer "B.SilkS")
		)
		(fp_line
			(start 1.524 -0.762)
			(end -1.524 -0.762)
			(stroke
				(width 0.1524)
				(type default)
			)
			(layer "B.SilkS")
		)
		(fp_line
			(start -1.1049 0.724916)
			(end -1.1049 -0.724916)
			(stroke
				(width 0.1)
				(type default)
			)
			(layer "B.Fab")
		)
		(fp_line
			(start 1.1049 0.724916)
			(end -1.1049 0.724916)
			(stroke
				(width 0.1)
				(type default)
			)
			(layer "B.Fab")
		)
		(fp_line
			(start -1.1049 -0.724916)
			(end 1.1049 -0.724916)
			(stroke
				(width 0.1)
				(type default)
			)
			(layer "B.Fab")
		)
		(fp_line
			(start 1.1049 -0.724916)
			(end 1.1049 0.724916)
			(stroke
				(width 0.1)
				(type default)
			)
			(layer "B.Fab")
		)
		(pad "1" smd rect
			(at 0.889 0 270)
			(size 1.016 1.27)
			(layers "B.Cu" "B.Mask" "B.Paste")
			(net "P1V8_CPU1_RT_1D")
		)
		(pad "2" smd rect
			(at -0.889 0 270)
			(size 1.016 1.27)
			(layers "B.Cu" "B.Mask" "B.Paste")
			(net "GND")
		)
	)
	(footprint ""
		(layer "B.Cu")
		(at 232.669842 -315.95568 -90)
		(property "Reference" "PC6530"
			(at 0 0 90)
			(layer "B.SilkS")
			(hide yes)
			(effects
				(font
					(size 1.27 1.27)
				)
				(justify mirror)
			)
		)
		(property "Value" ""
			(at 0 0 90)
			(layer "B.Fab")
			(effects
				(font
					(size 1.27 1.27)
				)
				(justify mirror)
			)
		)
		(duplicate_pad_numbers_are_jumpers no)
		(fp_line
			(start -1.524 0.762)
			(end 1.524 0.762)
			(stroke
				(width 0.1524)
				(type default)
			)
			(layer "B.SilkS")
		)
		(fp_line
			(start 1.524 0.762)
			(end 1.524 -0.762)
			(stroke
				(width 0.1524)
				(type default)
			)
			(layer "B.SilkS")
		)
		(fp_line
			(start -1.524 -0.762)
			(end -1.524 0.762)
			(stroke
				(width 0.1524)
				(type default)
			)
			(layer "B.SilkS")
		)
		(fp_line
			(start 1.524 -0.762)
			(end -1.524 -0.762)
			(stroke
				(width 0.1524)
				(type default)
			)
			(layer "B.SilkS")
		)
		(fp_line
			(start -1.1049 0.724916)
			(end -1.1049 -0.724916)
			(stroke
				(width 0.1)
				(type default)
			)
			(layer "B.Fab")
		)
		(fp_line
			(start 1.1049 0.724916)
			(end -1.1049 0.724916)
			(stroke
				(width 0.1)
				(type default)
			)
			(layer "B.Fab")
		)
		(fp_line
			(start -1.1049 -0.724916)
			(end 1.1049 -0.724916)
			(stroke
				(width 0.1)
				(type default)
			)
			(layer "B.Fab")
		)
		(fp_line
			(start 1.1049 -0.724916)
			(end 1.1049 0.724916)
			(stroke
				(width 0.1)
				(type default)
			)
			(layer "B.Fab")
		)
		(pad "1" smd rect
			(at 0.889 0 270)
			(size 1.016 1.27)
			(layers "B.Cu" "B.Mask" "B.Paste")
			(net "P1V8_CPU1_RT_1D")
		)
		(pad "2" smd rect
			(at -0.889 0 270)
			(size 1.016 1.27)
			(layers "B.Cu" "B.Mask" "B.Paste")
			(net "GND")
		)
	)
)
